(kicad_pcb
	(version 20260206)
	(generator "pcbnew")
	(generator_version "10.0")
	(general
		(thickness 1.6)
		(legacy_teardrops no)
	)
	(paper "A4")
	(title_block
		(title "03242023_DA0F0TMBIJ0_F0T_Motherboard_J_brd_V01_OCP.brd")
		(comment 1 "Grand Teton / footprints 760-766 of 6105")
	)
	(layers
		(0 "F.Cu" signal "TOP")
		(4 "In1.Cu" signal "GND")
		(6 "In2.Cu" signal "IN1")
		(8 "In3.Cu" signal "GND1")
		(10 "In4.Cu" signal "IN2")
		(12 "In5.Cu" signal "GND2")
		(14 "In6.Cu" signal "IN3")
		(16 "In7.Cu" signal "GND3")
		(18 "In8.Cu" signal "VCC")
		(20 "In9.Cu" signal "VCC1")
		(22 "In10.Cu" signal "GND4")
		(24 "In11.Cu" signal "IN4")
		(26 "In12.Cu" signal "GND5")
		(28 "In13.Cu" signal "IN5")
		(30 "In14.Cu" signal "GND6")
		(32 "In15.Cu" signal "IN6")
		(34 "In16.Cu" signal "GND7")
		(2 "B.Cu" signal "BOTTOM")
		(9 "F.Adhes" user "F.Adhesive")
		(11 "B.Adhes" user "B.Adhesive")
		(13 "F.Paste" user "Package Geometry/Pastemask Top")
		(15 "B.Paste" user "Package Geometry/Pastemask Bottom")
		(5 "F.SilkS" user "Ref Des/Silkscreen Top")
		(7 "B.SilkS" user "Ref Des/Silkscreen Bottom")
		(1 "F.Mask" user "Board Geometry/Soldermask Top")
		(3 "B.Mask" user "Board Geometry/Soldermask Bottom")
		(17 "Dwgs.User" user "User.Drawings")
		(19 "Cmts.User" user "User.Comments")
		(21 "Eco1.User" user "User.Eco1")
		(23 "Eco2.User" user "User.Eco2")
		(25 "Edge.Cuts" user "Board Geometry/Outline")
		(27 "Margin" user)
		(31 "F.CrtYd" user "Package Geometry/Place Bound Top")
		(29 "B.CrtYd" user "Package Geometry/Place Bound Bottom")
		(35 "F.Fab" user "Ref Des/Assembly Top")
		(33 "B.Fab" user "Ref Des/Assembly Bottom")
	)
	(footprint ""
		(layer "F.Cu")
		(at 437.240172 -32.173418 90)
		(property "Reference" "R3871"
			(at 0 0 90)
			(layer "F.SilkS")
			(hide yes)
			(effects
				(font
					(size 1.27 1.27)
				)
			)
		)
		(property "Value" ""
			(at 0 0 90)
			(layer "F.Fab")
			(effects
				(font
					(size 1.27 1.27)
				)
			)
		)
		(duplicate_pad_numbers_are_jumpers no)
		(fp_line
			(start 0.7874 -0.4064)
			(end 0.7874 0.4064)
			(stroke
				(width 0.1524)
				(type default)
			)
			(layer "F.SilkS")
		)
		(fp_line
			(start -0.7874 -0.4064)
			(end 0.7874 -0.4064)
			(stroke
				(width 0.1524)
				(type default)
			)
			(layer "F.SilkS")
		)
		(fp_line
			(start 0.7874 0.4064)
			(end -0.7874 0.4064)
			(stroke
				(width 0.1524)
				(type default)
			)
			(layer "F.SilkS")
		)
		(fp_line
			(start -0.7874 0.4064)
			(end -0.7874 -0.4064)
			(stroke
				(width 0.1524)
				(type default)
			)
			(layer "F.SilkS")
		)
		(fp_line
			(start -0.12065 -0.305054)
			(end -0.12065 -0.2794)
			(stroke
				(width 0.1)
				(type default)
			)
			(layer "F.Fab")
		)
		(fp_line
			(start -0.67945 -0.305054)
			(end -0.12065 -0.305054)
			(stroke
				(width 0.1)
				(type default)
			)
			(layer "F.Fab")
		)
		(fp_line
			(start 0.67945 -0.3048)
			(end 0.67945 0.3048)
			(stroke
				(width 0.1)
				(type default)
			)
			(layer "F.Fab")
		)
		(fp_line
			(start 0.12065 -0.3048)
			(end 0.67945 -0.3048)
			(stroke
				(width 0.1)
				(type default)
			)
			(layer "F.Fab")
		)
		(fp_line
			(start 0.12065 -0.2794)
			(end 0.12065 -0.3048)
			(stroke
				(width 0.1)
				(type default)
			)
			(layer "F.Fab")
		)
		(fp_line
			(start -0.12065 -0.2794)
			(end 0.12065 -0.2794)
			(stroke
				(width 0.1)
				(type default)
			)
			(layer "F.Fab")
		)
		(fp_line
			(start 0.120396 0.2794)
			(end -0.12065 0.2794)
			(stroke
				(width 0.1)
				(type default)
			)
			(layer "F.Fab")
		)
		(fp_line
			(start -0.12065 0.2794)
			(end -0.12065 0.3048)
			(stroke
				(width 0.1)
				(type default)
			)
			(layer "F.Fab")
		)
		(fp_line
			(start 0.67945 0.3048)
			(end 0.120396 0.3048)
			(stroke
				(width 0.1)
				(type default)
			)
			(layer "F.Fab")
		)
		(fp_line
			(start 0.120396 0.3048)
			(end 0.120396 0.2794)
			(stroke
				(width 0.1)
				(type default)
			)
			(layer "F.Fab")
		)
		(fp_line
			(start -0.12065 0.3048)
			(end -0.67945 0.3048)
			(stroke
				(width 0.1)
				(type default)
			)
			(layer "F.Fab")
		)
		(fp_line
			(start -0.67945 0.3048)
			(end -0.67945 -0.305054)
			(stroke
				(width 0.1)
				(type default)
			)
			(layer "F.Fab")
		)
		(pad "1" smd circle
			(at -0.40005 0 90)
			(size 0 0)
			(layers "F.Cu" "F.Mask" "F.Paste")
			(net "P12V_OCP_IMON_1")
		)
		(pad "2" smd circle
			(at 0.40005 0 90)
			(size 0 0)
			(layers "F.Cu" "F.Mask" "F.Paste")
			(net "P12V_OCP_SFF_ISENSE_MPS_MAM")
		)
	)
	(footprint ""
		(layer "F.Cu")
		(at 22.91588 -430.367948)
		(property "Reference" "R2910"
			(at 0 0 0)
			(layer "F.SilkS")
			(hide yes)
			(effects
				(font
					(size 1.27 1.27)
				)
			)
		)
		(property "Value" ""
			(at 0 0 0)
			(layer "F.Fab")
			(effects
				(font
					(size 1.27 1.27)
				)
			)
		)
		(duplicate_pad_numbers_are_jumpers no)
		(fp_line
			(start -0.7874 -0.4064)
			(end 0.7874 -0.4064)
			(stroke
				(width 0.1524)
				(type default)
			)
			(layer "F.SilkS")
		)
		(fp_line
			(start -0.7874 0.4064)
			(end -0.7874 -0.4064)
			(stroke
				(width 0.1524)
				(type default)
			)
			(layer "F.SilkS")
		)
		(fp_line
			(start 0.7874 -0.4064)
			(end 0.7874 0.4064)
			(stroke
				(width 0.1524)
				(type default)
			)
			(layer "F.SilkS")
		)
		(fp_line
			(start 0.7874 0.4064)
			(end -0.7874 0.4064)
			(stroke
				(width 0.1524)
				(type default)
			)
			(layer "F.SilkS")
		)
		(fp_line
			(start -0.67945 -0.305054)
			(end -0.12065 -0.305054)
			(stroke
				(width 0.1)
				(type default)
			)
			(layer "F.Fab")
		)
		(fp_line
			(start -0.67945 0.3048)
			(end -0.67945 -0.305054)
			(stroke
				(width 0.1)
				(type default)
			)
			(layer "F.Fab")
		)
		(fp_line
			(start -0.12065 -0.305054)
			(end -0.12065 -0.2794)
			(stroke
				(width 0.1)
				(type default)
			)
			(layer "F.Fab")
		)
		(fp_line
			(start -0.12065 -0.2794)
			(end 0.12065 -0.2794)
			(stroke
				(width 0.1)
				(type default)
			)
			(layer "F.Fab")
		)
		(fp_line
			(start -0.12065 0.2794)
			(end -0.12065 0.3048)
			(stroke
				(width 0.1)
				(type default)
			)
			(layer "F.Fab")
		)
		(fp_line
			(start -0.12065 0.3048)
			(end -0.67945 0.3048)
			(stroke
				(width 0.1)
				(type default)
			)
			(layer "F.Fab")
		)
		(fp_line
			(start 0.120396 0.2794)
			(end -0.12065 0.2794)
			(stroke
				(width 0.1)
				(type default)
			)
			(layer "F.Fab")
		)
		(fp_line
			(start 0.120396 0.3048)
			(end 0.120396 0.2794)
			(stroke
				(width 0.1)
				(type default)
			)
			(layer "F.Fab")
		)
		(fp_line
			(start 0.12065 -0.3048)
			(end 0.67945 -0.3048)
			(stroke
				(width 0.1)
				(type default)
			)
			(layer "F.Fab")
		)
		(fp_line
			(start 0.12065 -0.2794)
			(end 0.12065 -0.3048)
			(stroke
				(width 0.1)
				(type default)
			)
			(layer "F.Fab")
		)
		(fp_line
			(start 0.67945 -0.3048)
			(end 0.67945 0.3048)
			(stroke
				(width 0.1)
				(type default)
			)
			(layer "F.Fab")
		)
		(fp_line
			(start 0.67945 0.3048)
			(end 0.120396 0.3048)
			(stroke
				(width 0.1)
				(type default)
			)
			(layer "F.Fab")
		)
		(pad "1" smd circle
			(at -0.40005 0)
			(size 0 0)
			(layers "F.Cu" "F.Mask" "F.Paste")
			(net "P3V3_AUX")
		)
		(pad "2" smd circle
			(at 0.40005 0)
			(size 0 0)
			(layers "F.Cu" "F.Mask" "F.Paste")
			(net "FM_SWB_PWR_EN_R")
		)
	)
	(footprint ""
		(layer "F.Cu")
		(at 96.150938 -417.76777 90)
		(property "Reference" "R4186"
			(at 0 0 90)
			(layer "F.SilkS")
			(hide yes)
			(effects
				(font
					(size 1.27 1.27)
				)
			)
		)
		(property "Value" ""
			(at 0 0 90)
			(layer "F.Fab")
			(effects
				(font
					(size 1.27 1.27)
				)
			)
		)
		(duplicate_pad_numbers_are_jumpers no)
		(fp_line
			(start 0.7874 -0.4064)
			(end 0.7874 0.4064)
			(stroke
				(width 0.1524)
				(type default)
			)
			(layer "F.SilkS")
		)
		(fp_line
			(start -0.7874 -0.4064)
			(end 0.7874 -0.4064)
			(stroke
				(width 0.1524)
				(type default)
			)
			(layer "F.SilkS")
		)
		(fp_line
			(start 0.7874 0.4064)
			(end -0.7874 0.4064)
			(stroke
				(width 0.1524)
				(type default)
			)
			(layer "F.SilkS")
		)
		(fp_line
			(start -0.7874 0.4064)
			(end -0.7874 -0.4064)
			(stroke
				(width 0.1524)
				(type default)
			)
			(layer "F.SilkS")
		)
		(fp_line
			(start -0.12065 -0.305054)
			(end -0.12065 -0.2794)
			(stroke
				(width 0.1)
				(type default)
			)
			(layer "F.Fab")
		)
		(fp_line
			(start -0.67945 -0.305054)
			(end -0.12065 -0.305054)
			(stroke
				(width 0.1)
				(type default)
			)
			(layer "F.Fab")
		)
		(fp_line
			(start 0.67945 -0.3048)
			(end 0.67945 0.3048)
			(stroke
				(width 0.1)
				(type default)
			)
			(layer "F.Fab")
		)
		(fp_line
			(start 0.12065 -0.3048)
			(end 0.67945 -0.3048)
			(stroke
				(width 0.1)
				(type default)
			)
			(layer "F.Fab")
		)
		(fp_line
			(start 0.12065 -0.2794)
			(end 0.12065 -0.3048)
			(stroke
				(width 0.1)
				(type default)
			)
			(layer "F.Fab")
		)
		(fp_line
			(start -0.12065 -0.2794)
			(end 0.12065 -0.2794)
			(stroke
				(width 0.1)
				(type default)
			)
			(layer "F.Fab")
		)
		(fp_line
			(start 0.120396 0.2794)
			(end -0.12065 0.2794)
			(stroke
				(width 0.1)
				(type default)
			)
			(layer "F.Fab")
		)
		(fp_line
			(start -0.12065 0.2794)
			(end -0.12065 0.3048)
			(stroke
				(width 0.1)
				(type default)
			)
			(layer "F.Fab")
		)
		(fp_line
			(start 0.67945 0.3048)
			(end 0.120396 0.3048)
			(stroke
				(width 0.1)
				(type default)
			)
			(layer "F.Fab")
		)
		(fp_line
			(start 0.120396 0.3048)
			(end 0.120396 0.2794)
			(stroke
				(width 0.1)
				(type default)
			)
			(layer "F.Fab")
		)
		(fp_line
			(start -0.12065 0.3048)
			(end -0.67945 0.3048)
			(stroke
				(width 0.1)
				(type default)
			)
			(layer "F.Fab")
		)
		(fp_line
			(start -0.67945 0.3048)
			(end -0.67945 -0.305054)
			(stroke
				(width 0.1)
				(type default)
			)
			(layer "F.Fab")
		)
		(pad "1" smd circle
			(at -0.40005 0 90)
			(size 0 0)
			(layers "F.Cu" "F.Mask" "F.Paste")
			(net "P3V3_AUX")
		)
		(pad "2" smd circle
			(at 0.40005 0 90)
			(size 0 0)
			(layers "F.Cu" "F.Mask" "F.Paste")
			(net "U272_2_ADD2")
		)
	)
	(footprint ""
		(layer "F.Cu")
		(at 33.186878 -16.099536 90)
		(property "Reference" "C818"
			(at 0 0 90)
			(layer "F.SilkS")
			(hide yes)
			(effects
				(font
					(size 1.27 1.27)
				)
			)
		)
		(property "Value" ""
			(at 0 0 90)
			(layer "F.Fab")
			(effects
				(font
					(size 1.27 1.27)
				)
			)
		)
		(duplicate_pad_numbers_are_jumpers no)
		(fp_line
			(start 0.299974 -0.150114)
			(end 0.299974 0.150114)
			(stroke
				(width 0.1)
				(type default)
			)
			(layer "F.Fab")
		)
		(fp_line
			(start -0.299974 -0.150114)
			(end 0.299974 -0.150114)
			(stroke
				(width 0.1)
				(type default)
			)
			(layer "F.Fab")
		)
		(fp_line
			(start 0.299974 0.150114)
			(end -0.299974 0.150114)
			(stroke
				(width 0.1)
				(type default)
			)
			(layer "F.Fab")
		)
		(fp_line
			(start -0.299974 0.150114)
			(end -0.299974 -0.150114)
			(stroke
				(width 0.1)
				(type default)
			)
			(layer "F.Fab")
		)
		(pad "1" smd rect
			(at -0.2667 0 90)
			(size 0.3048 0.381)
			(layers "F.Cu" "F.Mask" "F.Paste")
			(net "P5E_CPU1_PE1_TX_C_DN<9>")
		)
		(pad "2" smd rect
			(at 0.2667 0 90)
			(size 0.3048 0.381)
			(layers "F.Cu" "F.Mask" "F.Paste")
			(net "P5E_CPU1_PE1_TX_DN<9>")
		)
	)
	(footprint ""
		(layer "F.Cu")
		(at 114.706654 -361.72775)
		(property "Reference" "PC555"
			(at 0 0 0)
			(layer "F.SilkS")
			(hide yes)
			(effects
				(font
					(size 1.27 1.27)
				)
			)
		)
		(property "Value" ""
			(at 0 0 0)
			(layer "F.Fab")
			(effects
				(font
					(size 1.27 1.27)
				)
			)
		)
		(duplicate_pad_numbers_are_jumpers no)
		(fp_line
			(start -0.7874 -0.4064)
			(end 0.7874 -0.4064)
			(stroke
				(width 0.1524)
				(type default)
			)
			(layer "F.SilkS")
		)
		(fp_line
			(start -0.7874 0.4064)
			(end -0.7874 -0.4064)
			(stroke
				(width 0.1524)
				(type default)
			)
			(layer "F.SilkS")
		)
		(fp_line
			(start 0.7874 -0.4064)
			(end 0.7874 0.4064)
			(stroke
				(width 0.1524)
				(type default)
			)
			(layer "F.SilkS")
		)
		(fp_line
			(start 0.7874 0.4064)
			(end -0.7874 0.4064)
			(stroke
				(width 0.1524)
				(type default)
			)
			(layer "F.SilkS")
		)
		(fp_line
			(start -0.67945 -0.305054)
			(end -0.12065 -0.305054)
			(stroke
				(width 0.1)
				(type default)
			)
			(layer "F.Fab")
		)
		(fp_line
			(start -0.67945 0.3048)
			(end -0.67945 -0.305054)
			(stroke
				(width 0.1)
				(type default)
			)
			(layer "F.Fab")
		)
		(fp_line
			(start -0.12065 -0.305054)
			(end -0.12065 -0.2794)
			(stroke
				(width 0.1)
				(type default)
			)
			(layer "F.Fab")
		)
		(fp_line
			(start -0.12065 -0.2794)
			(end 0.12065 -0.2794)
			(stroke
				(width 0.1)
				(type default)
			)
			(layer "F.Fab")
		)
		(fp_line
			(start -0.12065 0.2794)
			(end -0.12065 0.3048)
			(stroke
				(width 0.1)
				(type default)
			)
			(layer "F.Fab")
		)
		(fp_line
			(start -0.12065 0.3048)
			(end -0.67945 0.3048)
			(stroke
				(width 0.1)
				(type default)
			)
			(layer "F.Fab")
		)
		(fp_line
			(start 0.120396 0.2794)
			(end -0.12065 0.2794)
			(stroke
				(width 0.1)
				(type default)
			)
			(layer "F.Fab")
		)
		(fp_line
			(start 0.120396 0.3048)
			(end 0.120396 0.2794)
			(stroke
				(width 0.1)
				(type default)
			)
			(layer "F.Fab")
		)
		(fp_line
			(start 0.12065 -0.3048)
			(end 0.67945 -0.3048)
			(stroke
				(width 0.1)
				(type default)
			)
			(layer "F.Fab")
		)
		(fp_line
			(start 0.12065 -0.2794)
			(end 0.12065 -0.3048)
			(stroke
				(width 0.1)
				(type default)
			)
			(layer "F.Fab")
		)
		(fp_line
			(start 0.67945 -0.3048)
			(end 0.67945 0.3048)
			(stroke
				(width 0.1)
				(type default)
			)
			(layer "F.Fab")
		)
		(fp_line
			(start 0.67945 0.3048)
			(end 0.120396 0.3048)
			(stroke
				(width 0.1)
				(type default)
			)
			(layer "F.Fab")
		)
		(pad "1" smd circle
			(at -0.40005 0)
			(size 0 0)
			(layers "F.Cu" "F.Mask" "F.Paste")
			(net "PVCCIN_CPU1_VCC")
		)
		(pad "2" smd circle
			(at 0.40005 0)
			(size 0 0)
			(layers "F.Cu" "F.Mask" "F.Paste")
			(net "GND")
		)
	)
	(footprint ""
		(layer "F.Cu")
		(at 223.70288 -43.525948)
		(property "Reference" "R3533"
			(at 0 0 0)
			(layer "F.SilkS")
			(hide yes)
			(effects
				(font
					(size 1.27 1.27)
				)
			)
		)
		(property "Value" ""
			(at 0 0 0)
			(layer "F.Fab")
			(effects
				(font
					(size 1.27 1.27)
				)
			)
		)
		(duplicate_pad_numbers_are_jumpers no)
		(fp_line
			(start -0.7874 -0.4064)
			(end 0.7874 -0.4064)
			(stroke
				(width 0.1524)
				(type default)
			)
			(layer "F.SilkS")
		)
		(fp_line
			(start -0.7874 0.4064)
			(end -0.7874 -0.4064)
			(stroke
				(width 0.1524)
				(type default)
			)
			(layer "F.SilkS")
		)
		(fp_line
			(start 0.7874 -0.4064)
			(end 0.7874 0.4064)
			(stroke
				(width 0.1524)
				(type default)
			)
			(layer "F.SilkS")
		)
		(fp_line
			(start 0.7874 0.4064)
			(end -0.7874 0.4064)
			(stroke
				(width 0.1524)
				(type default)
			)
			(layer "F.SilkS")
		)
		(fp_line
			(start -0.67945 -0.305054)
			(end -0.12065 -0.305054)
			(stroke
				(width 0.1)
				(type default)
			)
			(layer "F.Fab")
		)
		(fp_line
			(start -0.67945 0.3048)
			(end -0.67945 -0.305054)
			(stroke
				(width 0.1)
				(type default)
			)
			(layer "F.Fab")
		)
		(fp_line
			(start -0.12065 -0.305054)
			(end -0.12065 -0.2794)
			(stroke
				(width 0.1)
				(type default)
			)
			(layer "F.Fab")
		)
		(fp_line
			(start -0.12065 -0.2794)
			(end 0.12065 -0.2794)
			(stroke
				(width 0.1)
				(type default)
			)
			(layer "F.Fab")
		)
		(fp_line
			(start -0.12065 0.2794)
			(end -0.12065 0.3048)
			(stroke
				(width 0.1)
				(type default)
			)
			(layer "F.Fab")
		)
		(fp_line
			(start -0.12065 0.3048)
			(end -0.67945 0.3048)
			(stroke
				(width 0.1)
				(type default)
			)
			(layer "F.Fab")
		)
		(fp_line
			(start 0.120396 0.2794)
			(end -0.12065 0.2794)
			(stroke
				(width 0.1)
				(type default)
			)
			(layer "F.Fab")
		)
		(fp_line
			(start 0.120396 0.3048)
			(end 0.120396 0.2794)
			(stroke
				(width 0.1)
				(type default)
			)
			(layer "F.Fab")
		)
		(fp_line
			(start 0.12065 -0.3048)
			(end 0.67945 -0.3048)
			(stroke
				(width 0.1)
				(type default)
			)
			(layer "F.Fab")
		)
		(fp_line
			(start 0.12065 -0.2794)
			(end 0.12065 -0.3048)
			(stroke
				(width 0.1)
				(type default)
			)
			(layer "F.Fab")
		)
		(fp_line
			(start 0.67945 -0.3048)
			(end 0.67945 0.3048)
			(stroke
				(width 0.1)
				(type default)
			)
			(layer "F.Fab")
		)
		(fp_line
			(start 0.67945 0.3048)
			(end 0.120396 0.3048)
			(stroke
				(width 0.1)
				(type default)
			)
			(layer "F.Fab")
		)
		(pad "1" smd circle
			(at -0.40005 0)
			(size 0 0)
			(layers "F.Cu" "F.Mask" "F.Paste")
			(net "SMB_E1S_3V3AUX_ISO_SCL_R")
		)
		(pad "2" smd circle
			(at 0.40005 0)
			(size 0 0)
			(layers "F.Cu" "F.Mask" "F.Paste")
			(net "SMB_E1S_3V3AUX_ISO_SCL")
		)
	)
	(footprint ""
		(layer "F.Cu")
		(at 322.8721 -76.585064 -90)
		(property "Reference" "R2974"
			(at 0 0 270)
			(layer "F.SilkS")
			(hide yes)
			(effects
				(font
					(size 1.27 1.27)
				)
			)
		)
		(property "Value" ""
			(at 0 0 270)
			(layer "F.Fab")
			(effects
				(font
					(size 1.27 1.27)
				)
			)
		)
		(duplicate_pad_numbers_are_jumpers no)
		(fp_line
			(start -0.7874 0.4064)
			(end -0.7874 -0.4064)
			(stroke
				(width 0.1524)
				(type default)
			)
			(layer "F.SilkS")
		)
		(fp_line
			(start 0.7874 0.4064)
			(end -0.7874 0.4064)
			(stroke
				(width 0.1524)
				(type default)
			)
			(layer "F.SilkS")
		)
		(fp_line
			(start -0.7874 -0.4064)
			(end 0.7874 -0.4064)
			(stroke
				(width 0.1524)
				(type default)
			)
			(layer "F.SilkS")
		)
		(fp_line
			(start 0.7874 -0.4064)
			(end 0.7874 0.4064)
			(stroke
				(width 0.1524)
				(type default)
			)
			(layer "F.SilkS")
		)
		(fp_line
			(start -0.67945 0.3048)
			(end -0.67945 -0.305054)
			(stroke
				(width 0.1)
				(type default)
			)
			(layer "F.Fab")
		)
		(fp_line
			(start -0.12065 0.3048)
			(end -0.67945 0.3048)
			(stroke
				(width 0.1)
				(type default)
			)
			(layer "F.Fab")
		)
		(fp_line
			(start 0.120396 0.3048)
			(end 0.120396 0.2794)
			(stroke
				(width 0.1)
				(type default)
			)
			(layer "F.Fab")
		)
		(fp_line
			(start 0.67945 0.3048)
			(end 0.120396 0.3048)
			(stroke
				(width 0.1)
				(type default)
			)
			(layer "F.Fab")
		)
		(fp_line
			(start -0.12065 0.2794)
			(end -0.12065 0.3048)
			(stroke
				(width 0.1)
				(type default)
			)
			(layer "F.Fab")
		)
		(fp_line
			(start 0.120396 0.2794)
			(end -0.12065 0.2794)
			(stroke
				(width 0.1)
				(type default)
			)
			(layer "F.Fab")
		)
		(fp_line
			(start -0.12065 -0.2794)
			(end 0.12065 -0.2794)
			(stroke
				(width 0.1)
				(type default)
			)
			(layer "F.Fab")
		)
		(fp_line
			(start 0.12065 -0.2794)
			(end 0.12065 -0.3048)
			(stroke
				(width 0.1)
				(type default)
			)
			(layer "F.Fab")
		)
		(fp_line
			(start 0.12065 -0.3048)
			(end 0.67945 -0.3048)
			(stroke
				(width 0.1)
				(type default)
			)
			(layer "F.Fab")
		)
		(fp_line
			(start 0.67945 -0.3048)
			(end 0.67945 0.3048)
			(stroke
				(width 0.1)
				(type default)
			)
			(layer "F.Fab")
		)
		(fp_line
			(start -0.67945 -0.305054)
			(end -0.12065 -0.305054)
			(stroke
				(width 0.1)
				(type default)
			)
			(layer "F.Fab")
		)
		(fp_line
			(start -0.12065 -0.305054)
			(end -0.12065 -0.2794)
			(stroke
				(width 0.1)
				(type default)
			)
			(layer "F.Fab")
		)
		(pad "1" smd circle
			(at -0.40005 0 270)
			(size 0 0)
			(layers "F.Cu" "F.Mask" "F.Paste")
			(net "P1V05_PCH_AUX")
		)
		(pad "2" smd circle
			(at 0.40005 0 270)
			(size 0 0)
			(layers "F.Cu" "F.Mask" "F.Paste")
			(net "FAB_REV_ID1")
		)
	)
)
